(kicad_pcb
	(version 20260206)
	(generator "pcbnew")
	(generator_version "10.0")
	(general
		(thickness 1.6)
		(legacy_teardrops no)
	)
	(paper "A4")
	(title_block
		(title "baseboard — 13948-1b.1110WZS1818.brd")
		(comment 1 "Honey Badger (Wiwynn) / footprints 326-332 of 2523")
	)
	(layers
		(0 "F.Cu" signal "TOP")
		(4 "In1.Cu" signal "L2GND")
		(6 "In2.Cu" signal "L3")
		(8 "In3.Cu" signal "L4VCC")
		(10 "In4.Cu" signal "L5VCC")
		(12 "In5.Cu" signal "L6")
		(14 "In6.Cu" signal "L7GND")
		(2 "B.Cu" signal "BOTTOM")
		(9 "F.Adhes" user "F.Adhesive")
		(11 "B.Adhes" user "B.Adhesive")
		(13 "F.Paste" user "Package Geometry/Pastemask Top")
		(15 "B.Paste" user "Package Geometry/Pastemask Bottom")
		(5 "F.SilkS" user "Ref Des/Silkscreen Top")
		(7 "B.SilkS" user "Ref Des/Silkscreen Bottom")
		(1 "F.Mask" user "Board Geometry/Soldermask Top")
		(3 "B.Mask" user "Board Geometry/Soldermask Bottom")
		(17 "Dwgs.User" user "User.Drawings")
		(19 "Cmts.User" user "User.Comments")
		(21 "Eco1.User" user "User.Eco1")
		(23 "Eco2.User" user "User.Eco2")
		(25 "Edge.Cuts" user "Board Geometry/Outline")
		(27 "Margin" user)
		(31 "F.CrtYd" user "Package Geometry/Place Bound Top")
		(29 "B.CrtYd" user "Package Geometry/Place Bound Bottom")
		(35 "F.Fab" user "Ref Des/Assembly Top")
		(33 "B.Fab" user "Ref Des/Assembly Bottom")
	)
	(footprint ""
		(layer "F.Cu")
		(at 104.775 -67.818)
		(property "Reference" "SR659"
			(at 0 0 0)
			(layer "F.SilkS")
			(hide yes)
			(effects
				(font
					(size 1.27 1.27)
				)
			)
		)
		(property "Value" "10KR2F-2-GP"
			(at 0.064008 -3.993896 0)
			(unlocked yes)
			(layer "F.Fab")
			(hide yes)
			(effects
				(font
					(size 1.016 1.016)
					(thickness 0.1524)
				)
			)
		)
		(property "Device Type" "R402H16"
			(at 0.064008 -5.517896 0)
			(unlocked yes)
			(layer "F.Fab")
			(hide yes)
			(effects
				(font
					(size 1.016 1.016)
					(thickness 0.1524)
				)
			)
		)
		(duplicate_pad_numbers_are_jumpers no)
		(fp_line
			(start -0.508 -0.9398)
			(end -0.508 0.9398)
			(stroke
				(width 0.1524)
				(type default)
			)
			(layer "F.SilkS")
		)
		(fp_line
			(start 0.508 -0.9398)
			(end -0.508 -0.9398)
			(stroke
				(width 0.1524)
				(type default)
			)
			(layer "F.SilkS")
		)
		(fp_rect
			(start -0.508 0.9398)
			(end 0.508 -0.9398)
			(stroke
				(width 0)
				(type default)
			)
			(fill no)
			(layer "F.CrtYd")
		)
		(fp_rect
			(start -0.508 0.9398)
			(end 0.508 -0.9398)
			(stroke
				(width 0)
				(type default)
			)
			(fill no)
			(layer "F.Fab")
		)
		(pad "1" smd custom
			(at 0 -0.4445)
			(size 0.1397 0.1397)
			(layers "F.Cu" "F.Mask" "F.Paste")
			(net "P1V8_C")
			(options
				(clearance outline)
				(anchor circle)
			)
			(primitives
				(gr_poly
					(pts
						(arc
							(start -0.1778 -0.2794)
							(mid -0.249642 -0.249642)
							(end -0.2794 -0.1778)
						)
						(arc
							(start -0.2794 0.1778)
							(mid -0.249642 0.249642)
							(end -0.1778 0.2794)
						)
						(arc
							(start 0.1778 0.2794)
							(mid 0.249642 0.249642)
							(end 0.2794 0.1778)
						)
						(arc
							(start 0.2794 -0.1778)
							(mid 0.249642 -0.249642)
							(end 0.1778 -0.2794)
						)
					)
					(width 0)
					(fill yes)
				)
			)
		)
		(pad "2" smd custom
			(at 0 0.4445)
			(size 0.1397 0.1397)
			(layers "F.Cu" "F.Mask" "F.Paste")
			(net "LSI_TN")
			(options
				(clearance outline)
				(anchor circle)
			)
			(primitives
				(gr_poly
					(pts
						(arc
							(start -0.1778 -0.2794)
							(mid -0.249642 -0.249642)
							(end -0.2794 -0.1778)
						)
						(arc
							(start -0.2794 0.1778)
							(mid -0.249642 0.249642)
							(end -0.1778 0.2794)
						)
						(arc
							(start 0.1778 0.2794)
							(mid 0.249642 0.249642)
							(end 0.2794 0.1778)
						)
						(arc
							(start 0.2794 -0.1778)
							(mid 0.249642 -0.249642)
							(end 0.1778 -0.2794)
						)
					)
					(width 0)
					(fill yes)
				)
			)
		)
	)
	(footprint ""
		(layer "F.Cu")
		(at 92.28201 -101.727 -90)
		(property "Reference" "SR820"
			(at 0 0 270)
			(layer "F.SilkS")
			(hide yes)
			(effects
				(font
					(size 1.27 1.27)
				)
			)
		)
		(property "Value" "1KR2F-3-GP"
			(at 0.064008 -3.993896 270)
			(unlocked yes)
			(layer "F.Fab")
			(hide yes)
			(effects
				(font
					(size 1.016 1.016)
					(thickness 0.1524)
				)
			)
		)
		(property "Device Type" "R402H16"
			(at 0.064008 -5.517896 270)
			(unlocked yes)
			(layer "F.Fab")
			(hide yes)
			(effects
				(font
					(size 1.016 1.016)
					(thickness 0.1524)
				)
			)
		)
		(duplicate_pad_numbers_are_jumpers no)
		(fp_line
			(start -0.508 -0.9398)
			(end -0.508 0.9398)
			(stroke
				(width 0.1524)
				(type default)
			)
			(layer "F.SilkS")
		)
		(fp_line
			(start 0.508 -0.9398)
			(end -0.508 -0.9398)
			(stroke
				(width 0.1524)
				(type default)
			)
			(layer "F.SilkS")
		)
		(fp_rect
			(start -0.508 0.9398)
			(end 0.508 -0.9398)
			(stroke
				(width 0)
				(type default)
			)
			(fill no)
			(layer "F.CrtYd")
		)
		(fp_rect
			(start -0.508 0.9398)
			(end 0.508 -0.9398)
			(stroke
				(width 0)
				(type default)
			)
			(fill no)
			(layer "F.Fab")
		)
		(pad "1" smd custom
			(at 0 -0.4445 270)
			(size 0.1397 0.1397)
			(layers "F.Cu" "F.Mask" "F.Paste")
			(net "UART_CTS")
			(options
				(clearance outline)
				(anchor circle)
			)
			(primitives
				(gr_poly
					(pts
						(arc
							(start -0.1778 -0.2794)
							(mid -0.249642 -0.249642)
							(end -0.2794 -0.1778)
						)
						(arc
							(start -0.2794 0.1778)
							(mid -0.249642 0.249642)
							(end -0.1778 0.2794)
						)
						(arc
							(start 0.1778 0.2794)
							(mid 0.249642 0.249642)
							(end 0.2794 0.1778)
						)
						(arc
							(start 0.2794 -0.1778)
							(mid 0.249642 -0.249642)
							(end 0.1778 -0.2794)
						)
					)
					(width 0)
					(fill yes)
				)
			)
		)
		(pad "2" smd custom
			(at 0 0.4445 270)
			(size 0.1397 0.1397)
			(layers "F.Cu" "F.Mask" "F.Paste")
			(net "P1V8_E")
			(options
				(clearance outline)
				(anchor circle)
			)
			(primitives
				(gr_poly
					(pts
						(arc
							(start -0.1778 -0.2794)
							(mid -0.249642 -0.249642)
							(end -0.2794 -0.1778)
						)
						(arc
							(start -0.2794 0.1778)
							(mid -0.249642 0.249642)
							(end -0.1778 0.2794)
						)
						(arc
							(start 0.1778 0.2794)
							(mid 0.249642 0.249642)
							(end 0.2794 0.1778)
						)
						(arc
							(start 0.2794 -0.1778)
							(mid 0.249642 -0.249642)
							(end 0.1778 -0.2794)
						)
					)
					(width 0)
					(fill yes)
				)
			)
		)
	)
	(footprint ""
		(layer "F.Cu")
		(at 256.667 -115.189)
		(property "Reference" "R7901"
			(at 0 0 0)
			(layer "F.SilkS")
			(hide yes)
			(effects
				(font
					(size 1.27 1.27)
				)
			)
		)
		(property "Value" "0R2J-2-GP"
			(at 0.064008 -3.993896 0)
			(unlocked yes)
			(layer "F.Fab")
			(hide yes)
			(effects
				(font
					(size 1.016 1.016)
					(thickness 0.1524)
				)
			)
		)
		(property "Device Type" "R402H16"
			(at 0.064008 -5.517896 0)
			(unlocked yes)
			(layer "F.Fab")
			(hide yes)
			(effects
				(font
					(size 1.016 1.016)
					(thickness 0.1524)
				)
			)
		)
		(duplicate_pad_numbers_are_jumpers no)
		(fp_line
			(start -0.508 -0.9398)
			(end -0.508 0.9398)
			(stroke
				(width 0.1524)
				(type default)
			)
			(layer "F.SilkS")
		)
		(fp_line
			(start 0.508 -0.9398)
			(end -0.508 -0.9398)
			(stroke
				(width 0.1524)
				(type default)
			)
			(layer "F.SilkS")
		)
		(fp_rect
			(start -0.508 0.9398)
			(end 0.508 -0.9398)
			(stroke
				(width 0)
				(type default)
			)
			(fill no)
			(layer "F.CrtYd")
		)
		(fp_rect
			(start -0.508 0.9398)
			(end 0.508 -0.9398)
			(stroke
				(width 0)
				(type default)
			)
			(fill no)
			(layer "F.Fab")
		)
		(pad "1" smd custom
			(at 0 -0.4445)
			(size 0.1397 0.1397)
			(layers "F.Cu" "F.Mask" "F.Paste")
			(net "CPU_RXD_R")
			(options
				(clearance outline)
				(anchor circle)
			)
			(primitives
				(gr_poly
					(pts
						(arc
							(start -0.1778 -0.2794)
							(mid -0.249642 -0.249642)
							(end -0.2794 -0.1778)
						)
						(arc
							(start -0.2794 0.1778)
							(mid -0.249642 0.249642)
							(end -0.1778 0.2794)
						)
						(arc
							(start 0.1778 0.2794)
							(mid 0.249642 0.249642)
							(end 0.2794 0.1778)
						)
						(arc
							(start 0.2794 -0.1778)
							(mid 0.249642 -0.249642)
							(end 0.1778 -0.2794)
						)
					)
					(width 0)
					(fill yes)
				)
			)
		)
		(pad "2" smd custom
			(at 0 0.4445)
			(size 0.1397 0.1397)
			(layers "F.Cu" "F.Mask" "F.Paste")
			(net "CPU_RXD")
			(options
				(clearance outline)
				(anchor circle)
			)
			(primitives
				(gr_poly
					(pts
						(arc
							(start -0.1778 -0.2794)
							(mid -0.249642 -0.249642)
							(end -0.2794 -0.1778)
						)
						(arc
							(start -0.2794 0.1778)
							(mid -0.249642 0.249642)
							(end -0.1778 0.2794)
						)
						(arc
							(start 0.1778 0.2794)
							(mid 0.249642 0.249642)
							(end 0.2794 0.1778)
						)
						(arc
							(start 0.2794 -0.1778)
							(mid 0.249642 -0.249642)
							(end 0.1778 -0.2794)
						)
					)
					(width 0)
					(fill yes)
				)
			)
		)
	)
	(footprint ""
		(layer "F.Cu")
		(at 337.058 -83.947)
		(property "Reference" "R264"
			(at 0 0 0)
			(layer "F.SilkS")
			(hide yes)
			(effects
				(font
					(size 1.27 1.27)
				)
			)
		)
		(property "Value" "2K2R2J-2-GP"
			(at 0.064008 -3.993896 0)
			(unlocked yes)
			(layer "F.Fab")
			(hide yes)
			(effects
				(font
					(size 1.016 1.016)
					(thickness 0.1524)
				)
			)
		)
		(property "Device Type" "R402H16"
			(at 0.064008 -5.517896 0)
			(unlocked yes)
			(layer "F.Fab")
			(hide yes)
			(effects
				(font
					(size 1.016 1.016)
					(thickness 0.1524)
				)
			)
		)
		(duplicate_pad_numbers_are_jumpers no)
		(fp_line
			(start -0.508 -0.9398)
			(end -0.508 0.9398)
			(stroke
				(width 0.1524)
				(type default)
			)
			(layer "F.SilkS")
		)
		(fp_line
			(start 0.508 -0.9398)
			(end -0.508 -0.9398)
			(stroke
				(width 0.1524)
				(type default)
			)
			(layer "F.SilkS")
		)
		(fp_rect
			(start -0.508 0.9398)
			(end 0.508 -0.9398)
			(stroke
				(width 0)
				(type default)
			)
			(fill no)
			(layer "F.CrtYd")
		)
		(fp_rect
			(start -0.508 0.9398)
			(end 0.508 -0.9398)
			(stroke
				(width 0)
				(type default)
			)
			(fill no)
			(layer "F.Fab")
		)
		(pad "1" smd custom
			(at 0 -0.4445)
			(size 0.1397 0.1397)
			(layers "F.Cu" "F.Mask" "F.Paste")
			(net "P3V3_STBY")
			(options
				(clearance outline)
				(anchor circle)
			)
			(primitives
				(gr_poly
					(pts
						(arc
							(start -0.1778 -0.2794)
							(mid -0.249642 -0.249642)
							(end -0.2794 -0.1778)
						)
						(arc
							(start -0.2794 0.1778)
							(mid -0.249642 0.249642)
							(end -0.1778 0.2794)
						)
						(arc
							(start 0.1778 0.2794)
							(mid 0.249642 0.249642)
							(end 0.2794 0.1778)
						)
						(arc
							(start 0.2794 -0.1778)
							(mid 0.249642 -0.249642)
							(end 0.1778 -0.2794)
						)
					)
					(width 0)
					(fill yes)
				)
			)
		)
		(pad "2" smd custom
			(at 0 0.4445)
			(size 0.1397 0.1397)
			(layers "F.Cu" "F.Mask" "F.Paste")
			(net "FLA_CS_R")
			(options
				(clearance outline)
				(anchor circle)
			)
			(primitives
				(gr_poly
					(pts
						(arc
							(start -0.1778 -0.2794)
							(mid -0.249642 -0.249642)
							(end -0.2794 -0.1778)
						)
						(arc
							(start -0.2794 0.1778)
							(mid -0.249642 0.249642)
							(end -0.1778 0.2794)
						)
						(arc
							(start 0.1778 0.2794)
							(mid 0.249642 0.249642)
							(end 0.2794 0.1778)
						)
						(arc
							(start 0.2794 -0.1778)
							(mid 0.249642 -0.249642)
							(end 0.1778 -0.2794)
						)
					)
					(width 0)
					(fill yes)
				)
			)
		)
	)
	(footprint ""
		(layer "F.Cu")
		(at 164.211 -112.903 -90)
		(property "Reference" "PR152"
			(at 0 0 270)
			(layer "F.SilkS")
			(hide yes)
			(effects
				(font
					(size 1.27 1.27)
				)
			)
		)
		(property "Value" "0R2J-2-GP"
			(at 0.064008 -3.993896 270)
			(unlocked yes)
			(layer "F.Fab")
			(hide yes)
			(effects
				(font
					(size 1.016 1.016)
					(thickness 0.1524)
				)
			)
		)
		(property "Device Type" "R402H16"
			(at 0.064008 -5.517896 270)
			(unlocked yes)
			(layer "F.Fab")
			(hide yes)
			(effects
				(font
					(size 1.016 1.016)
					(thickness 0.1524)
				)
			)
		)
		(duplicate_pad_numbers_are_jumpers no)
		(fp_line
			(start -0.508 -0.9398)
			(end -0.508 0.9398)
			(stroke
				(width 0.1524)
				(type default)
			)
			(layer "F.SilkS")
		)
		(fp_line
			(start 0.508 -0.9398)
			(end -0.508 -0.9398)
			(stroke
				(width 0.1524)
				(type default)
			)
			(layer "F.SilkS")
		)
		(fp_rect
			(start -0.508 0.9398)
			(end 0.508 -0.9398)
			(stroke
				(width 0)
				(type default)
			)
			(fill no)
			(layer "F.CrtYd")
		)
		(fp_rect
			(start -0.508 0.9398)
			(end 0.508 -0.9398)
			(stroke
				(width 0)
				(type default)
			)
			(fill no)
			(layer "F.Fab")
		)
		(pad "1" smd custom
			(at 0 -0.4445 270)
			(size 0.1397 0.1397)
			(layers "F.Cu" "F.Mask" "F.Paste")
			(net "P0V9_E_EN")
			(options
				(clearance outline)
				(anchor circle)
			)
			(primitives
				(gr_poly
					(pts
						(arc
							(start -0.1778 -0.2794)
							(mid -0.249642 -0.249642)
							(end -0.2794 -0.1778)
						)
						(arc
							(start -0.2794 0.1778)
							(mid -0.249642 0.249642)
							(end -0.1778 0.2794)
						)
						(arc
							(start 0.1778 0.2794)
							(mid 0.249642 0.249642)
							(end 0.2794 0.1778)
						)
						(arc
							(start 0.2794 -0.1778)
							(mid 0.249642 -0.249642)
							(end 0.1778 -0.2794)
						)
					)
					(width 0)
					(fill yes)
				)
			)
		)
		(pad "2" smd custom
			(at 0 0.4445 270)
			(size 0.1397 0.1397)
			(layers "F.Cu" "F.Mask" "F.Paste")
			(net "P1V5_E_PG")
			(options
				(clearance outline)
				(anchor circle)
			)
			(primitives
				(gr_poly
					(pts
						(arc
							(start -0.1778 -0.2794)
							(mid -0.249642 -0.249642)
							(end -0.2794 -0.1778)
						)
						(arc
							(start -0.2794 0.1778)
							(mid -0.249642 0.249642)
							(end -0.1778 0.2794)
						)
						(arc
							(start 0.1778 0.2794)
							(mid 0.249642 0.249642)
							(end 0.2794 0.1778)
						)
						(arc
							(start 0.2794 -0.1778)
							(mid 0.249642 -0.249642)
							(end 0.1778 -0.2794)
						)
					)
					(width 0)
					(fill yes)
				)
			)
		)
	)
	(footprint ""
		(layer "F.Cu")
		(at 291.592 -151.638 90)
		(property "Reference" "R400"
			(at 0 0 90)
			(layer "F.SilkS")
			(hide yes)
			(effects
				(font
					(size 1.27 1.27)
				)
			)
		)
		(property "Value" "10KR2F-2-GP"
			(at 0.064008 -3.993896 90)
			(unlocked yes)
			(layer "F.Fab")
			(hide yes)
			(effects
				(font
					(size 1.016 1.016)
					(thickness 0.1524)
				)
			)
		)
		(property "Device Type" "R402H16"
			(at 0.064008 -5.517896 90)
			(unlocked yes)
			(layer "F.Fab")
			(hide yes)
			(effects
				(font
					(size 1.016 1.016)
					(thickness 0.1524)
				)
			)
		)
		(duplicate_pad_numbers_are_jumpers no)
		(fp_line
			(start 0.508 -0.9398)
			(end -0.508 -0.9398)
			(stroke
				(width 0.1524)
				(type default)
			)
			(layer "F.SilkS")
		)
		(fp_line
			(start -0.508 -0.9398)
			(end -0.508 0.9398)
			(stroke
				(width 0.1524)
				(type default)
			)
			(layer "F.SilkS")
		)
		(fp_rect
			(start -0.508 0.9398)
			(end 0.508 -0.9398)
			(stroke
				(width 0)
				(type default)
			)
			(fill no)
			(layer "F.CrtYd")
		)
		(fp_rect
			(start -0.508 0.9398)
			(end 0.508 -0.9398)
			(stroke
				(width 0)
				(type default)
			)
			(fill no)
			(layer "F.Fab")
		)
		(pad "1" smd custom
			(at 0 -0.4445 90)
			(size 0.1397 0.1397)
			(layers "F.Cu" "F.Mask" "F.Paste")
			(net "P3V3_STBY")
			(options
				(clearance outline)
				(anchor circle)
			)
			(primitives
				(gr_poly
					(pts
						(arc
							(start -0.1778 -0.2794)
							(mid -0.249642 -0.249642)
							(end -0.2794 -0.1778)
						)
						(arc
							(start -0.2794 0.1778)
							(mid -0.249642 0.249642)
							(end -0.1778 0.2794)
						)
						(arc
							(start 0.1778 0.2794)
							(mid 0.249642 0.249642)
							(end 0.2794 0.1778)
						)
						(arc
							(start 0.2794 -0.1778)
							(mid 0.249642 -0.249642)
							(end 0.1778 -0.2794)
						)
					)
					(width 0)
					(fill yes)
				)
			)
		)
		(pad "2" smd custom
			(at 0 0.4445 90)
			(size 0.1397 0.1397)
			(layers "F.Cu" "F.Mask" "F.Paste")
			(net "50M_CLK_OE")
			(options
				(clearance outline)
				(anchor circle)
			)
			(primitives
				(gr_poly
					(pts
						(arc
							(start -0.1778 -0.2794)
							(mid -0.249642 -0.249642)
							(end -0.2794 -0.1778)
						)
						(arc
							(start -0.2794 0.1778)
							(mid -0.249642 0.249642)
							(end -0.1778 0.2794)
						)
						(arc
							(start 0.1778 0.2794)
							(mid 0.249642 0.249642)
							(end 0.2794 0.1778)
						)
						(arc
							(start 0.2794 -0.1778)
							(mid 0.249642 -0.249642)
							(end 0.1778 -0.2794)
						)
					)
					(width 0)
					(fill yes)
				)
			)
		)
	)
	(footprint ""
		(layer "F.Cu")
		(at 304.038 -216.789 180)
		(property "Reference" "R647"
			(at 0 0 180)
			(layer "F.SilkS")
			(hide yes)
			(effects
				(font
					(size 1.27 1.27)
				)
			)
		)
		(property "Value" "4K7R2F-GP"
			(at 0.064008 -3.993896 180)
			(unlocked yes)
			(layer "F.Fab")
			(hide yes)
			(effects
				(font
					(size 1.016 1.016)
					(thickness 0.1524)
				)
			)
		)
		(property "Device Type" "R402H16"
			(at 0.064008 -5.517896 180)
			(unlocked yes)
			(layer "F.Fab")
			(hide yes)
			(effects
				(font
					(size 1.016 1.016)
					(thickness 0.1524)
				)
			)
		)
		(duplicate_pad_numbers_are_jumpers no)
		(fp_line
			(start 0.508 -0.9398)
			(end -0.508 -0.9398)
			(stroke
				(width 0.1524)
				(type default)
			)
			(layer "F.SilkS")
		)
		(fp_line
			(start -0.508 -0.9398)
			(end -0.508 0.9398)
			(stroke
				(width 0.1524)
				(type default)
			)
			(layer "F.SilkS")
		)
		(fp_rect
			(start -0.508 0.9398)
			(end 0.508 -0.9398)
			(stroke
				(width 0)
				(type default)
			)
			(fill no)
			(layer "F.CrtYd")
		)
		(fp_rect
			(start -0.508 0.9398)
			(end 0.508 -0.9398)
			(stroke
				(width 0)
				(type default)
			)
			(fill no)
			(layer "F.Fab")
		)
		(pad "1" smd custom
			(at 0 -0.4445 180)
			(size 0.1397 0.1397)
			(layers "F.Cu" "F.Mask" "F.Paste")
			(net "P3V3_STBY")
			(options
				(clearance outline)
				(anchor circle)
			)
			(primitives
				(gr_poly
					(pts
						(arc
							(start -0.1778 -0.2794)
							(mid -0.249642 -0.249642)
							(end -0.2794 -0.1778)
						)
						(arc
							(start -0.2794 0.1778)
							(mid -0.249642 0.249642)
							(end -0.1778 0.2794)
						)
						(arc
							(start 0.1778 0.2794)
							(mid 0.249642 0.249642)
							(end 0.2794 0.1778)
						)
						(arc
							(start 0.2794 -0.1778)
							(mid 0.249642 -0.249642)
							(end 0.1778 -0.2794)
						)
					)
					(width 0)
					(fill yes)
				)
			)
		)
		(pad "2" smd custom
			(at 0 0.4445 180)
			(size 0.1397 0.1397)
			(layers "F.Cu" "F.Mask" "F.Paste")
			(net "BMC_DEBUG_OE_1_N")
			(options
				(clearance outline)
				(anchor circle)
			)
			(primitives
				(gr_poly
					(pts
						(arc
							(start -0.1778 -0.2794)
							(mid -0.249642 -0.249642)
							(end -0.2794 -0.1778)
						)
						(arc
							(start -0.2794 0.1778)
							(mid -0.249642 0.249642)
							(end -0.1778 0.2794)
						)
						(arc
							(start 0.1778 0.2794)
							(mid 0.249642 0.249642)
							(end 0.2794 0.1778)
						)
						(arc
							(start 0.2794 -0.1778)
							(mid 0.249642 -0.249642)
							(end 0.1778 -0.2794)
						)
					)
					(width 0)
					(fill yes)
				)
			)
		)
	)
)
